(kicad_pcb
	(version 20211014)
	(generator pcbnew)
	(general
    (thickness 1.6)
  )
	(paper "A4")
	(title_block
    (title "SA800U (Snapdragon 845) Baseboard")
    (date "2023-10-19")
    (rev "1.0.3")
    (company "Antmicro Ltd.")
    (comment 1 "www.antmicro.com")
		(comment 9 "footprints 506-520 of 589")
	)
	(layers
    (0 "F.Cu" signal)
    (1 "In1.Cu" power)
    (2 "In2.Cu" signal)
    (3 "In3.Cu" signal)
    (4 "In4.Cu" power)
    (31 "B.Cu" signal)
    (32 "B.Adhes" user "B.Adhesive")
    (33 "F.Adhes" user "F.Adhesive")
    (34 "B.Paste" user)
    (35 "F.Paste" user)
    (36 "B.SilkS" user "B.Silkscreen")
    (37 "F.SilkS" user "F.Silkscreen")
    (38 "B.Mask" user)
    (39 "F.Mask" user)
    (40 "Dwgs.User" user "User.Drawings")
    (41 "Cmts.User" user "User.Comments")
    (42 "Eco1.User" user "User.Eco1")
    (43 "Eco2.User" user "User.Eco2")
    (44 "Edge.Cuts" user)
    (45 "Margin" user)
    (46 "B.CrtYd" user "B.Courtyard")
    (47 "F.CrtYd" user "F.Courtyard")
    (48 "B.Fab" user)
    (49 "F.Fab" user)
  )
	(footprint "sa800u-baseboard-hw-footprints:TP_SMD_0.75mm" (layer "B.Cu")
    (tedit 5E4A9375)
    (at 142.9 132.7492)
    (property "Author" "Antmicro")
    (property "License" "Apache-2.0")
    (property "MPN" "")
    (property "Manufacturer" "")
    (property "Sheetfile" "hdmi-converter.kicad_sch")
    (property "Sheetname" "HDMI converter")
    (attr smd)
    (fp_text reference "TP15" (at 0.43 0.3408 270) (layer "B.SilkS")
      (effects (font (size 0.7 0.7) (thickness 0.15)) (justify left bottom mirror))
    )
    (fp_text value "TP_0.75mm_SMD" (at 0 -1.2 180) (layer "B.Fab")
      (effects (font (size 0.7 0.7) (thickness 0.15)) (justify left bottom mirror))
    )
    (fp_text user "License: Apache-2.0" (at -0.4 -5.101 180) (layer "B.Fab") hide
      (effects (font (size 0.7 0.7) (thickness 0.15)) (justify left bottom mirror))
    )
    (fp_text user "${REFERENCE}" (at -0.4 -2.7 180) (layer "B.Fab") hide
      (effects (font (size 0.7 0.7) (thickness 0.15)) (justify left bottom mirror))
    )
    (fp_text user "Author: Antmicro" (at -0.4 -3.901 180) (layer "B.Fab") hide
      (effects (font (size 0.7 0.7) (thickness 0.15)) (justify left bottom mirror))
    )
    (pad "1" smd circle (at 0 0) (size 0.75 0.75) (layers "B.Cu" "B.Mask")
      (net 191 "/HDMI converter/LT9611_VCC12_TX") (pinfunction "1") (pintype "passive"))
  )
	(footprint "sa800u-baseboard-hw-footprints:TP_SMD_0.75mm" (layer "B.Cu")
    (tedit 5E4A9375)
    (at 137.2 131.9492)
    (property "Author" "Antmicro")
    (property "License" "Apache-2.0")
    (property "MPN" "")
    (property "Manufacturer" "")
    (property "Sheetfile" "hdmi-converter.kicad_sch")
    (property "Sheetname" "HDMI converter")
    (attr smd)
    (fp_text reference "TP16" (at 0.62 1.2408 180) (layer "B.SilkS")
      (effects (font (size 0.7 0.7) (thickness 0.15)) (justify left bottom mirror))
    )
    (fp_text value "TP_0.75mm_SMD" (at 0 -1.2 180) (layer "B.Fab")
      (effects (font (size 0.7 0.7) (thickness 0.15)) (justify left bottom mirror))
    )
    (fp_text user "License: Apache-2.0" (at -0.4 -5.101 180) (layer "B.Fab") hide
      (effects (font (size 0.7 0.7) (thickness 0.15)) (justify left bottom mirror))
    )
    (fp_text user "Author: Antmicro" (at -0.4 -3.901 180) (layer "B.Fab") hide
      (effects (font (size 0.7 0.7) (thickness 0.15)) (justify left bottom mirror))
    )
    (fp_text user "${REFERENCE}" (at -0.4 -2.7 180) (layer "B.Fab") hide
      (effects (font (size 0.7 0.7) (thickness 0.15)) (justify left bottom mirror))
    )
    (pad "1" smd circle (at 0 0) (size 0.75 0.75) (layers "B.Cu" "B.Mask")
      (net 232 "/HDMI converter/HDMI_SCL") (pinfunction "1") (pintype "passive"))
  )
	(footprint "sa800u-baseboard-hw-footprints:TP_SMD_0.75mm" (layer "B.Cu")
    (tedit 5E4A9375)
    (at 137.2 130.8)
    (property "Author" "Antmicro")
    (property "License" "Apache-2.0")
    (property "MPN" "")
    (property "Manufacturer" "")
    (property "Sheetfile" "hdmi-converter.kicad_sch")
    (property "Sheetname" "HDMI converter")
    (attr smd)
    (fp_text reference "TP19" (at -0.32 1.14 180) (layer "B.SilkS")
      (effects (font (size 0.7 0.7) (thickness 0.15)) (justify left bottom mirror))
    )
    (fp_text value "TP_0.75mm_SMD" (at 0 -1.2 180) (layer "B.Fab")
      (effects (font (size 0.7 0.7) (thickness 0.15)) (justify left bottom mirror))
    )
    (fp_text user "${REFERENCE}" (at -0.4 -2.7 180) (layer "B.Fab") hide
      (effects (font (size 0.7 0.7) (thickness 0.15)) (justify left bottom mirror))
    )
    (fp_text user "License: Apache-2.0" (at -0.4 -5.101 180) (layer "B.Fab") hide
      (effects (font (size 0.7 0.7) (thickness 0.15)) (justify left bottom mirror))
    )
    (fp_text user "Author: Antmicro" (at -0.4 -3.901 180) (layer "B.Fab") hide
      (effects (font (size 0.7 0.7) (thickness 0.15)) (justify left bottom mirror))
    )
    (pad "1" smd circle (at 0 0) (size 0.75 0.75) (layers "B.Cu" "B.Mask")
      (net 235 "/HDMI converter/HDMI_SDA") (pinfunction "1") (pintype "passive"))
  )
	(footprint "sa800u-baseboard-hw-footprints:TP_SMD_0.75mm" (layer "B.Cu")
    (tedit 5E4A9375)
    (at 142 126.5)
    (property "Author" "Antmicro")
    (property "License" "Apache-2.0")
    (property "MPN" "")
    (property "Manufacturer" "")
    (property "Sheetfile" "hdmi-converter.kicad_sch")
    (property "Sheetname" "HDMI converter")
    (attr smd)
    (fp_text reference "TP20" (at 1.09 -0.31 180) (layer "B.SilkS")
      (effects (font (size 0.7 0.7) (thickness 0.15)) (justify left bottom mirror))
    )
    (fp_text value "TP_0.75mm_SMD" (at 0 -1.2 180) (layer "B.Fab")
      (effects (font (size 0.7 0.7) (thickness 0.15)) (justify left bottom mirror))
    )
    (fp_text user "${REFERENCE}" (at -0.4 -2.7 180) (layer "B.Fab") hide
      (effects (font (size 0.7 0.7) (thickness 0.15)) (justify left bottom mirror))
    )
    (fp_text user "Author: Antmicro" (at -0.4 -3.901 180) (layer "B.Fab") hide
      (effects (font (size 0.7 0.7) (thickness 0.15)) (justify left bottom mirror))
    )
    (fp_text user "License: Apache-2.0" (at -0.4 -5.101 180) (layer "B.Fab") hide
      (effects (font (size 0.7 0.7) (thickness 0.15)) (justify left bottom mirror))
    )
    (pad "1" smd circle (at 0 0) (size 0.75 0.75) (layers "B.Cu" "B.Mask")
      (net 285 "/HDMI converter/LT9611_CEC") (pinfunction "1") (pintype "passive"))
  )
	(footprint "sa800u-baseboard-hw-footprints:TP_SMD_0.75mm" (layer "B.Cu")
    (tedit 5E4A9375)
    (at 143.3 141.15)
    (property "Author" "Antmicro")
    (property "License" "Apache-2.0")
    (property "MPN" "")
    (property "Manufacturer" "")
    (property "Sheetfile" "hdmi-converter.kicad_sch")
    (property "Sheetname" "HDMI converter")
    (attr smd)
    (fp_text reference "TP21" (at -0.35 0.35 180) (layer "B.SilkS")
      (effects (font (size 0.7 0.7) (thickness 0.15)) (justify left bottom mirror))
    )
    (fp_text value "TP_0.75mm_SMD" (at 0 -1.2 180) (layer "B.Fab")
      (effects (font (size 0.7 0.7) (thickness 0.15)) (justify left bottom mirror))
    )
    (fp_text user "Author: Antmicro" (at -0.4 -3.901 180) (layer "B.Fab") hide
      (effects (font (size 0.7 0.7) (thickness 0.15)) (justify left bottom mirror))
    )
    (fp_text user "${REFERENCE}" (at -0.4 -2.7 180) (layer "B.Fab") hide
      (effects (font (size 0.7 0.7) (thickness 0.15)) (justify left bottom mirror))
    )
    (fp_text user "License: Apache-2.0" (at -0.4 -5.101 180) (layer "B.Fab") hide
      (effects (font (size 0.7 0.7) (thickness 0.15)) (justify left bottom mirror))
    )
    (pad "1" smd circle (at 0 0) (size 0.75 0.75) (layers "B.Cu" "B.Mask")
      (net 234 "/HDMI converter/HDMI_DETECT") (pinfunction "1") (pintype "passive"))
  )
	(footprint "sa800u-baseboard-hw-footprints:TP_SMD_0.75mm" (layer "B.Cu")
    (tedit 5E4A9375)
    (at 142.05 136.9992)
    (property "Author" "Antmicro")
    (property "License" "Apache-2.0")
    (property "MPN" "")
    (property "Manufacturer" "")
    (property "Sheetfile" "hdmi-converter.kicad_sch")
    (property "Sheetname" "HDMI converter")
    (attr smd)
    (fp_text reference "TP22" (at -0.26 0.3608 180) (layer "B.SilkS")
      (effects (font (size 0.7 0.7) (thickness 0.15)) (justify left bottom mirror))
    )
    (fp_text value "TP_0.75mm_SMD" (at 0 -1.2 180) (layer "B.Fab")
      (effects (font (size 0.7 0.7) (thickness 0.15)) (justify left bottom mirror))
    )
    (fp_text user "Author: Antmicro" (at -0.4 -3.901 180) (layer "B.Fab") hide
      (effects (font (size 0.7 0.7) (thickness 0.15)) (justify left bottom mirror))
    )
    (fp_text user "${REFERENCE}" (at -0.4 -2.7 180) (layer "B.Fab") hide
      (effects (font (size 0.7 0.7) (thickness 0.15)) (justify left bottom mirror))
    )
    (fp_text user "License: Apache-2.0" (at -0.4 -5.101 180) (layer "B.Fab") hide
      (effects (font (size 0.7 0.7) (thickness 0.15)) (justify left bottom mirror))
    )
    (pad "1" smd circle (at 0 0) (size 0.75 0.75) (layers "B.Cu" "B.Mask")
      (net 209 "/HDMI converter/VCOM") (pinfunction "1") (pintype "passive"))
  )
	(footprint "sa800u-baseboard-hw-footprints:TP_SMD_0.75mm" (layer "B.Cu")
    (tedit 5E4A9375)
    (at 132.2 108.8)
    (property "Author" "Antmicro")
    (property "License" "Apache-2.0")
    (property "MPN" "")
    (property "Manufacturer" "")
    (property "Sheetfile" "hdmi-converter.kicad_sch")
    (property "Sheetname" "HDMI converter")
    (attr smd)
    (fp_text reference "TP23" (at 0.44 0.34 270) (layer "B.SilkS")
      (effects (font (size 0.7 0.7) (thickness 0.15)) (justify left bottom mirror))
    )
    (fp_text value "TP_0.75mm_SMD" (at 0 -1.2 180) (layer "B.Fab")
      (effects (font (size 0.7 0.7) (thickness 0.15)) (justify left bottom mirror))
    )
    (fp_text user "License: Apache-2.0" (at -0.4 -5.101 180) (layer "B.Fab") hide
      (effects (font (size 0.7 0.7) (thickness 0.15)) (justify left bottom mirror))
    )
    (fp_text user "Author: Antmicro" (at -0.4 -3.901 180) (layer "B.Fab") hide
      (effects (font (size 0.7 0.7) (thickness 0.15)) (justify left bottom mirror))
    )
    (fp_text user "${REFERENCE}" (at -0.4 -2.7 180) (layer "B.Fab") hide
      (effects (font (size 0.7 0.7) (thickness 0.15)) (justify left bottom mirror))
    )
    (pad "1" smd circle (at 0 0) (size 0.75 0.75) (layers "B.Cu" "B.Mask")
      (net 40 "I2C4_SDA") (pinfunction "1") (pintype "passive"))
  )
	(footprint "sa800u-baseboard-hw-footprints:TP_SMD_0.75mm" (layer "B.Cu")
    (tedit 5E4A9375)
    (at 128.9 106)
    (property "Author" "Antmicro")
    (property "License" "Apache-2.0")
    (property "MPN" "")
    (property "Manufacturer" "")
    (property "Sheetfile" "hdmi-converter.kicad_sch")
    (property "Sheetname" "HDMI converter")
    (attr smd)
    (fp_text reference "TP24" (at -0.26 0.36 180) (layer "B.SilkS")
      (effects (font (size 0.7 0.7) (thickness 0.15)) (justify left bottom mirror))
    )
    (fp_text value "TP_0.75mm_SMD" (at 0 -1.2 180) (layer "B.Fab")
      (effects (font (size 0.7 0.7) (thickness 0.15)) (justify left bottom mirror))
    )
    (fp_text user "Author: Antmicro" (at -0.4 -3.901 180) (layer "B.Fab") hide
      (effects (font (size 0.7 0.7) (thickness 0.15)) (justify left bottom mirror))
    )
    (fp_text user "License: Apache-2.0" (at -0.4 -5.101 180) (layer "B.Fab") hide
      (effects (font (size 0.7 0.7) (thickness 0.15)) (justify left bottom mirror))
    )
    (fp_text user "${REFERENCE}" (at -0.4 -2.7 180) (layer "B.Fab") hide
      (effects (font (size 0.7 0.7) (thickness 0.15)) (justify left bottom mirror))
    )
    (pad "1" smd circle (at 0 0) (size 0.75 0.75) (layers "B.Cu" "B.Mask")
      (net 41 "I2C4_SCL") (pinfunction "1") (pintype "passive"))
  )
	(footprint "sa800u-baseboard-hw-footprints:TP_SMD_0.75mm" (layer "B.Cu")
    (tedit 5E4A9375)
    (at 142 125)
    (property "Author" "Antmicro")
    (property "License" "Apache-2.0")
    (property "MPN" "")
    (property "Manufacturer" "")
    (property "Sheetfile" "hdmi-converter.kicad_sch")
    (property "Sheetname" "HDMI converter")
    (attr smd)
    (fp_text reference "TP25" (at 1.13 -0.32 180) (layer "B.SilkS")
      (effects (font (size 0.7 0.7) (thickness 0.15)) (justify left bottom mirror))
    )
    (fp_text value "TP_0.75mm_SMD" (at 0 -1.2 180) (layer "B.Fab")
      (effects (font (size 0.7 0.7) (thickness 0.15)) (justify left bottom mirror))
    )
    (fp_text user "License: Apache-2.0" (at -0.4 -5.101 180) (layer "B.Fab") hide
      (effects (font (size 0.7 0.7) (thickness 0.15)) (justify left bottom mirror))
    )
    (fp_text user "${REFERENCE}" (at -0.4 -2.7 180) (layer "B.Fab") hide
      (effects (font (size 0.7 0.7) (thickness 0.15)) (justify left bottom mirror))
    )
    (fp_text user "Author: Antmicro" (at -0.4 -3.901 180) (layer "B.Fab") hide
      (effects (font (size 0.7 0.7) (thickness 0.15)) (justify left bottom mirror))
    )
    (pad "1" smd circle (at 0 0) (size 0.75 0.75) (layers "B.Cu" "B.Mask")
      (net 287 "/HDMI converter/LT9611_SCL") (pinfunction "1") (pintype "passive"))
  )
	(footprint "sa800u-baseboard-hw-footprints:TP_SMD_0.75mm" (layer "B.Cu")
    (tedit 5E4A9375)
    (at 140.25 125)
    (property "Author" "Antmicro")
    (property "License" "Apache-2.0")
    (property "MPN" "")
    (property "Manufacturer" "")
    (property "Sheetfile" "hdmi-converter.kicad_sch")
    (property "Sheetname" "HDMI converter")
    (attr smd)
    (fp_text reference "TP26" (at -0.29 0.35 180) (layer "B.SilkS")
      (effects (font (size 0.7 0.7) (thickness 0.15)) (justify left bottom mirror))
    )
    (fp_text value "TP_0.75mm_SMD" (at 0 -1.2 180) (layer "B.Fab")
      (effects (font (size 0.7 0.7) (thickness 0.15)) (justify left bottom mirror))
    )
    (fp_text user "Author: Antmicro" (at -0.4 -3.901 180) (layer "B.Fab") hide
      (effects (font (size 0.7 0.7) (thickness 0.15)) (justify left bottom mirror))
    )
    (fp_text user "License: Apache-2.0" (at -0.4 -5.101 180) (layer "B.Fab") hide
      (effects (font (size 0.7 0.7) (thickness 0.15)) (justify left bottom mirror))
    )
    (fp_text user "${REFERENCE}" (at -0.4 -2.7 180) (layer "B.Fab") hide
      (effects (font (size 0.7 0.7) (thickness 0.15)) (justify left bottom mirror))
    )
    (pad "1" smd circle (at 0 0) (size 0.75 0.75) (layers "B.Cu" "B.Mask")
      (net 288 "/HDMI converter/LT9611_SDA") (pinfunction "1") (pintype "passive"))
  )
	(footprint "sa800u-baseboard-hw-footprints:TP_SMD_0.75mm" (layer "B.Cu")
    (tedit 5E4A9375)
    (at 109.6 94.1)
    (property "Author" "Antmicro")
    (property "License" "Apache-2.0")
    (property "MPN" "")
    (property "Manufacturer" "")
    (property "Sheetfile" "camera-interface.kicad_sch")
    (property "Sheetname" "Camera Interface")
    (attr smd)
    (fp_text reference "TP30" (at 1.11 1.29 180) (layer "B.SilkS")
      (effects (font (size 0.7 0.7) (thickness 0.15)) (justify left bottom mirror))
    )
    (fp_text value "TP_0.75mm_SMD" (at 0 -1.2 180) (layer "B.Fab")
      (effects (font (size 0.7 0.7) (thickness 0.15)) (justify left bottom mirror))
    )
    (fp_text user "Author: Antmicro" (at -0.4 -3.901 180) (layer "B.Fab") hide
      (effects (font (size 0.7 0.7) (thickness 0.15)) (justify left bottom mirror))
    )
    (fp_text user "License: Apache-2.0" (at -0.4 -5.101 180) (layer "B.Fab") hide
      (effects (font (size 0.7 0.7) (thickness 0.15)) (justify left bottom mirror))
    )
    (fp_text user "${REFERENCE}" (at -0.4 -2.7 180) (layer "B.Fab") hide
      (effects (font (size 0.7 0.7) (thickness 0.15)) (justify left bottom mirror))
    )
    (pad "1" smd circle (at 0 0) (size 0.75 0.75) (layers "B.Cu" "B.Mask")
      (net 43 "CCI0_I2C_SDA") (pinfunction "1") (pintype "passive"))
  )
	(footprint "sa800u-baseboard-hw-footprints:TP_SMD_0.75mm" (layer "B.Cu")
    (tedit 5E4A9375)
    (at 117.4 92.7)
    (property "Author" "Antmicro")
    (property "License" "Apache-2.0")
    (property "MPN" "")
    (property "Manufacturer" "")
    (property "Sheetfile" "camera-interface.kicad_sch")
    (property "Sheetname" "Camera Interface")
    (attr smd)
    (fp_text reference "TP34" (at 1.22 -0.42 180) (layer "B.SilkS")
      (effects (font (size 0.7 0.7) (thickness 0.15)) (justify left bottom mirror))
    )
    (fp_text value "TP_0.75mm_SMD" (at 0 -1.2 180) (layer "B.Fab")
      (effects (font (size 0.7 0.7) (thickness 0.15)) (justify left bottom mirror))
    )
    (fp_text user "${REFERENCE}" (at -0.4 -2.7 180) (layer "B.Fab") hide
      (effects (font (size 0.7 0.7) (thickness 0.15)) (justify left bottom mirror))
    )
    (fp_text user "License: Apache-2.0" (at -0.4 -5.101 180) (layer "B.Fab") hide
      (effects (font (size 0.7 0.7) (thickness 0.15)) (justify left bottom mirror))
    )
    (fp_text user "Author: Antmicro" (at -0.4 -3.901 180) (layer "B.Fab") hide
      (effects (font (size 0.7 0.7) (thickness 0.15)) (justify left bottom mirror))
    )
    (pad "1" smd circle (at 0 0) (size 0.75 0.75) (layers "B.Cu" "B.Mask")
      (net 231 "/Camera Interface/3V3_CAM") (pinfunction "1") (pintype "passive"))
  )
	(footprint "sa800u-baseboard-hw-footprints:TP_SMD_0.75mm" (layer "B.Cu")
    (tedit 5E4A9375)
    (at 111.15 92.26)
    (property "Author" "Antmicro")
    (property "License" "Apache-2.0")
    (property "MPN" "")
    (property "Manufacturer" "")
    (property "Sheetfile" "camera-interface.kicad_sch")
    (property "Sheetname" "Camera Interface")
    (attr smd)
    (fp_text reference "TP36" (at 1.67 -0.4592 180) (layer "B.SilkS")
      (effects (font (size 0.7 0.7) (thickness 0.15)) (justify left bottom mirror))
    )
    (fp_text value "TP_0.75mm_SMD" (at 0 -1.2 180) (layer "B.Fab")
      (effects (font (size 0.7 0.7) (thickness 0.15)) (justify left bottom mirror))
    )
    (fp_text user "Author: Antmicro" (at -0.4 -3.901 180) (layer "B.Fab") hide
      (effects (font (size 0.7 0.7) (thickness 0.15)) (justify left bottom mirror))
    )
    (fp_text user "${REFERENCE}" (at -0.4 -2.7 180) (layer "B.Fab") hide
      (effects (font (size 0.7 0.7) (thickness 0.15)) (justify left bottom mirror))
    )
    (fp_text user "License: Apache-2.0" (at -0.4 -5.101 180) (layer "B.Fab") hide
      (effects (font (size 0.7 0.7) (thickness 0.15)) (justify left bottom mirror))
    )
    (pad "1" smd circle (at 0 0) (size 0.75 0.75) (layers "B.Cu" "B.Mask")
      (net 294 "/Camera Interface/CCI0_I2C_SCL_3V3") (pinfunction "1") (pintype "passive"))
  )
	(footprint "sa800u-baseboard-hw-footprints:TP_SMD_0.75mm" (layer "B.Cu")
    (tedit 5E4A9375)
    (at 112.97 92.81)
    (property "Author" "Antmicro")
    (property "License" "Apache-2.0")
    (property "MPN" "")
    (property "Manufacturer" "")
    (property "Sheetfile" "camera-interface.kicad_sch")
    (property "Sheetname" "Camera Interface")
    (attr smd)
    (fp_text reference "TP37" (at 1.47 1.27 180) (layer "B.SilkS")
      (effects (font (size 0.7 0.7) (thickness 0.15)) (justify left bottom mirror))
    )
    (fp_text value "TP_0.75mm_SMD" (at 0 -1.2 180) (layer "B.Fab")
      (effects (font (size 0.7 0.7) (thickness 0.15)) (justify left bottom mirror))
    )
    (fp_text user "Author: Antmicro" (at -0.4 -3.901 180) (layer "B.Fab") hide
      (effects (font (size 0.7 0.7) (thickness 0.15)) (justify left bottom mirror))
    )
    (fp_text user "License: Apache-2.0" (at -0.4 -5.101 180) (layer "B.Fab") hide
      (effects (font (size 0.7 0.7) (thickness 0.15)) (justify left bottom mirror))
    )
    (fp_text user "${REFERENCE}" (at -0.4 -2.7 180) (layer "B.Fab") hide
      (effects (font (size 0.7 0.7) (thickness 0.15)) (justify left bottom mirror))
    )
    (pad "1" smd circle (at 0 0) (size 0.75 0.75) (layers "B.Cu" "B.Mask")
      (net 295 "/Camera Interface/CCI1_I2C_SDA_3V3") (pinfunction "1") (pintype "passive"))
  )
	(footprint "sa800u-baseboard-hw-footprints:TP_SMD_0.75mm" (layer "B.Cu")
    (tedit 5E4A9375)
    (at 109.8 92.0492)
    (property "Author" "Antmicro")
    (property "License" "Apache-2.0")
    (property "MPN" "")
    (property "Manufacturer" "")
    (property "Sheetfile" "camera-interface.kicad_sch")
    (property "Sheetname" "Camera Interface")
    (attr smd)
    (fp_text reference "TP38" (at 0.93 1.2308 180) (layer "B.SilkS")
      (effects (font (size 0.7 0.7) (thickness 0.15)) (justify left bottom mirror))
    )
    (fp_text value "TP_0.75mm_SMD" (at 0 -1.2 180) (layer "B.Fab")
      (effects (font (size 0.7 0.7) (thickness 0.15)) (justify left bottom mirror))
    )
    (fp_text user "License: Apache-2.0" (at -0.4 -5.101 180) (layer "B.Fab") hide
      (effects (font (size 0.7 0.7) (thickness 0.15)) (justify left bottom mirror))
    )
    (fp_text user "Author: Antmicro" (at -0.4 -3.901 180) (layer "B.Fab") hide
      (effects (font (size 0.7 0.7) (thickness 0.15)) (justify left bottom mirror))
    )
    (fp_text user "${REFERENCE}" (at -0.4 -2.7 180) (layer "B.Fab") hide
      (effects (font (size 0.7 0.7) (thickness 0.15)) (justify left bottom mirror))
    )
    (pad "1" smd circle (at 0 0) (size 0.75 0.75) (layers "B.Cu" "B.Mask")
      (net 296 "/Camera Interface/CCI0_I2C_SDA_3V3") (pinfunction "1") (pintype "passive"))
  )
)
